# S9S_MB_2U (Grand Teton) — schematic netlist excerpt (pin names and nets, part order shuffled) for the footprints in the layout excerpt that follows; sources: Cadence DE-HDL packaged netlist, KiCad conversion of 03242023_DA0F0TMBIJ0_F0T_Motherboard_J_brd_V01_OCP.brd

C1568  Q_CAP_DIFFBUS  DIFF BUS_0.22UF 6.3V 20% X6S  pkg C0201  page 175 : \1\ = P5E_CPU0_PE4_TX_C_DN<5> ; \2\ = P5E_CPU0_PE4_TX_DN<5>
R2917  Q_RES  49.9 1% CHIP  pkg 0402LF  page 151 : A = BMC_MONITER_BUF_R ; B = BMC_MONITER_BUF
R4800  Q_RES  4.7K 5% CHIP  pkg 0402LF  page 144 : A = P3V3_AUX ; B = PRSNT_CABLE_GPU_A3

(kicad_pcb
	(version 20260206)
	(generator "pcbnew")
	(generator_version "10.0")
	(general
		(thickness 1.6)
		(legacy_teardrops no)
	)
	(paper "A4")
	(title_block
		(title "03242023_DA0F0TMBIJ0_F0T_Motherboard_J_brd_V01_OCP.brd")
		(comment 1 "Grand Teton / footprints 1989-1991 of 6105")
	)
	(layers
		(0 "F.Cu" signal "TOP")
		(4 "In1.Cu" signal "GND")
		(6 "In2.Cu" signal "IN1")
		(8 "In3.Cu" signal "GND1")
		(10 "In4.Cu" signal "IN2")
		(12 "In5.Cu" signal "GND2")
		(14 "In6.Cu" signal "IN3")
		(16 "In7.Cu" signal "GND3")
		(18 "In8.Cu" signal "VCC")
		(20 "In9.Cu" signal "VCC1")
		(22 "In10.Cu" signal "GND4")
		(24 "In11.Cu" signal "IN4")
		(26 "In12.Cu" signal "GND5")
		(28 "In13.Cu" signal "IN5")
		(30 "In14.Cu" signal "GND6")
		(32 "In15.Cu" signal "IN6")
		(34 "In16.Cu" signal "GND7")
		(2 "B.Cu" signal "BOTTOM")
		(9 "F.Adhes" user "F.Adhesive")
		(11 "B.Adhes" user "B.Adhesive")
		(13 "F.Paste" user "Package Geometry/Pastemask Top")
		(15 "B.Paste" user "Package Geometry/Pastemask Bottom")
		(5 "F.SilkS" user "Ref Des/Silkscreen Top")
		(7 "B.SilkS" user "Ref Des/Silkscreen Bottom")
		(1 "F.Mask" user "Board Geometry/Soldermask Top")
		(3 "B.Mask" user "Board Geometry/Soldermask Bottom")
		(17 "Dwgs.User" user "User.Drawings")
		(19 "Cmts.User" user "User.Comments")
		(21 "Eco1.User" user "User.Eco1")
		(23 "Eco2.User" user "User.Eco2")
		(25 "Edge.Cuts" user "Board Geometry/Outline")
		(27 "Margin" user)
		(31 "F.CrtYd" user "Package Geometry/Place Bound Top")
		(29 "B.CrtYd" user "Package Geometry/Place Bound Bottom")
		(35 "F.Fab" user "Ref Des/Assembly Top")
		(33 "B.Fab" user "Ref Des/Assembly Bottom")
	)
	(footprint ""
		(layer "F.Cu")
		(at 176.17948 -425.414948)
		(property "Reference" "R2917"
			(at 0 0 0)
			(layer "F.SilkS")
			(hide yes)
			(effects
				(font
					(size 1.27 1.27)
				)
			)
		)
		(property "Value" ""
			(at 0 0 0)
			(layer "F.Fab")
			(effects
				(font
					(size 1.27 1.27)
				)
			)
		)
		(duplicate_pad_numbers_are_jumpers no)
		(fp_line
			(start -0.7874 -0.4064)
			(end 0.7874 -0.4064)
			(stroke
				(width 0.1524)
				(type default)
			)
			(layer "F.SilkS")
		)
		(fp_line
			(start -0.7874 0.4064)
			(end -0.7874 -0.4064)
			(stroke
				(width 0.1524)
				(type default)
			)
			(layer "F.SilkS")
		)
		(fp_line
			(start 0.7874 -0.4064)
			(end 0.7874 0.4064)
			(stroke
				(width 0.1524)
				(type default)
			)
			(layer "F.SilkS")
		)
		(fp_line
			(start 0.7874 0.4064)
			(end -0.7874 0.4064)
			(stroke
				(width 0.1524)
				(type default)
			)
			(layer "F.SilkS")
		)
		(fp_line
			(start -0.67945 -0.305054)
			(end -0.12065 -0.305054)
			(stroke
				(width 0.1)
				(type default)
			)
			(layer "F.Fab")
		)
		(fp_line
			(start -0.67945 0.3048)
			(end -0.67945 -0.305054)
			(stroke
				(width 0.1)
				(type default)
			)
			(layer "F.Fab")
		)
		(fp_line
			(start -0.12065 -0.305054)
			(end -0.12065 -0.2794)
			(stroke
				(width 0.1)
				(type default)
			)
			(layer "F.Fab")
		)
		(fp_line
			(start -0.12065 -0.2794)
			(end 0.12065 -0.2794)
			(stroke
				(width 0.1)
				(type default)
			)
			(layer "F.Fab")
		)
		(fp_line
			(start -0.12065 0.2794)
			(end -0.12065 0.3048)
			(stroke
				(width 0.1)
				(type default)
			)
			(layer "F.Fab")
		)
		(fp_line
			(start -0.12065 0.3048)
			(end -0.67945 0.3048)
			(stroke
				(width 0.1)
				(type default)
			)
			(layer "F.Fab")
		)
		(fp_line
			(start 0.120396 0.2794)
			(end -0.12065 0.2794)
			(stroke
				(width 0.1)
				(type default)
			)
			(layer "F.Fab")
		)
		(fp_line
			(start 0.120396 0.3048)
			(end 0.120396 0.2794)
			(stroke
				(width 0.1)
				(type default)
			)
			(layer "F.Fab")
		)
		(fp_line
			(start 0.12065 -0.3048)
			(end 0.67945 -0.3048)
			(stroke
				(width 0.1)
				(type default)
			)
			(layer "F.Fab")
		)
		(fp_line
			(start 0.12065 -0.2794)
			(end 0.12065 -0.3048)
			(stroke
				(width 0.1)
				(type default)
			)
			(layer "F.Fab")
		)
		(fp_line
			(start 0.67945 -0.3048)
			(end 0.67945 0.3048)
			(stroke
				(width 0.1)
				(type default)
			)
			(layer "F.Fab")
		)
		(fp_line
			(start 0.67945 0.3048)
			(end 0.120396 0.3048)
			(stroke
				(width 0.1)
				(type default)
			)
			(layer "F.Fab")
		)
		(pad "1" smd circle
			(at -0.40005 0)
			(size 0 0)
			(layers "F.Cu" "F.Mask" "F.Paste")
			(net "BMC_MONITER_BUF_R")
		)
		(pad "2" smd circle
			(at 0.40005 0)
			(size 0 0)
			(layers "F.Cu" "F.Mask" "F.Paste")
			(net "BMC_MONITER_BUF")
		)
	)
	(footprint ""
		(layer "F.Cu")
		(at 319.270888 -402.371052 -90)
		(property "Reference" "C1568"
			(at 0 0 270)
			(layer "F.SilkS")
			(hide yes)
			(effects
				(font
					(size 1.27 1.27)
				)
			)
		)
		(property "Value" ""
			(at 0 0 270)
			(layer "F.Fab")
			(effects
				(font
					(size 1.27 1.27)
				)
			)
		)
		(duplicate_pad_numbers_are_jumpers no)
		(fp_line
			(start -0.299974 0.150114)
			(end -0.299974 -0.150114)
			(stroke
				(width 0.1)
				(type default)
			)
			(layer "F.Fab")
		)
		(fp_line
			(start 0.299974 0.150114)
			(end -0.299974 0.150114)
			(stroke
				(width 0.1)
				(type default)
			)
			(layer "F.Fab")
		)
		(fp_line
			(start -0.299974 -0.150114)
			(end 0.299974 -0.150114)
			(stroke
				(width 0.1)
				(type default)
			)
			(layer "F.Fab")
		)
		(fp_line
			(start 0.299974 -0.150114)
			(end 0.299974 0.150114)
			(stroke
				(width 0.1)
				(type default)
			)
			(layer "F.Fab")
		)
		(pad "1" smd rect
			(at -0.2667 0 270)
			(size 0.3048 0.381)
			(layers "F.Cu" "F.Mask" "F.Paste")
			(net "P5E_CPU0_PE4_TX_C_DN<5>")
		)
		(pad "2" smd rect
			(at 0.2667 0 270)
			(size 0.3048 0.381)
			(layers "F.Cu" "F.Mask" "F.Paste")
			(net "P5E_CPU0_PE4_TX_DN<5>")
		)
	)
	(footprint ""
		(layer "F.Cu")
		(at 358.76865 -412.0388)
		(property "Reference" "R4800"
			(at 0 0 0)
			(layer "F.SilkS")
			(hide yes)
			(effects
				(font
					(size 1.27 1.27)
				)
			)
		)
		(property "Value" ""
			(at 0 0 0)
			(layer "F.Fab")
			(effects
				(font
					(size 1.27 1.27)
				)
			)
		)
		(duplicate_pad_numbers_are_jumpers no)
		(fp_line
			(start -0.7874 -0.4064)
			(end 0.7874 -0.4064)
			(stroke
				(width 0.1524)
				(type default)
			)
			(layer "F.SilkS")
		)
		(fp_line
			(start -0.7874 0.4064)
			(end -0.7874 -0.4064)
			(stroke
				(width 0.1524)
				(type default)
			)
			(layer "F.SilkS")
		)
		(fp_line
			(start 0.7874 -0.4064)
			(end 0.7874 0.4064)
			(stroke
				(width 0.1524)
				(type default)
			)
			(layer "F.SilkS")
		)
		(fp_line
			(start 0.7874 0.4064)
			(end -0.7874 0.4064)
			(stroke
				(width 0.1524)
				(type default)
			)
			(layer "F.SilkS")
		)
		(fp_line
			(start -0.67945 -0.305054)
			(end -0.12065 -0.305054)
			(stroke
				(width 0.1)
				(type default)
			)
			(layer "F.Fab")
		)
		(fp_line
			(start -0.67945 0.3048)
			(end -0.67945 -0.305054)
			(stroke
				(width 0.1)
				(type default)
			)
			(layer "F.Fab")
		)
		(fp_line
			(start -0.12065 -0.305054)
			(end -0.12065 -0.2794)
			(stroke
				(width 0.1)
				(type default)
			)
			(layer "F.Fab")
		)
		(fp_line
			(start -0.12065 -0.2794)
			(end 0.12065 -0.2794)
			(stroke
				(width 0.1)
				(type default)
			)
			(layer "F.Fab")
		)
		(fp_line
			(start -0.12065 0.2794)
			(end -0.12065 0.3048)
			(stroke
				(width 0.1)
				(type default)
			)
			(layer "F.Fab")
		)
		(fp_line
			(start -0.12065 0.3048)
			(end -0.67945 0.3048)
			(stroke
				(width 0.1)
				(type default)
			)
			(layer "F.Fab")
		)
		(fp_line
			(start 0.120396 0.2794)
			(end -0.12065 0.2794)
			(stroke
				(width 0.1)
				(type default)
			)
			(layer "F.Fab")
		)
		(fp_line
			(start 0.120396 0.3048)
			(end 0.120396 0.2794)
			(stroke
				(width 0.1)
				(type default)
			)
			(layer "F.Fab")
		)
		(fp_line
			(start 0.12065 -0.3048)
			(end 0.67945 -0.3048)
			(stroke
				(width 0.1)
				(type default)
			)
			(layer "F.Fab")
		)
		(fp_line
			(start 0.12065 -0.2794)
			(end 0.12065 -0.3048)
			(stroke
				(width 0.1)
				(type default)
			)
			(layer "F.Fab")
		)
		(fp_line
			(start 0.67945 -0.3048)
			(end 0.67945 0.3048)
			(stroke
				(width 0.1)
				(type default)
			)
			(layer "F.Fab")
		)
		(fp_line
			(start 0.67945 0.3048)
			(end 0.120396 0.3048)
			(stroke
				(width 0.1)
				(type default)
			)
			(layer "F.Fab")
		)
		(pad "1" smd circle
			(at -0.40005 0)
			(size 0 0)
			(layers "F.Cu" "F.Mask" "F.Paste")
			(net "P3V3_AUX")
		)
		(pad "2" smd circle
			(at 0.40005 0)
			(size 0 0)
			(layers "F.Cu" "F.Mask" "F.Paste")
			(net "PRSNT_CABLE_GPU_A3")
		)
	)
)
